# T6G (Grand Teton) — schematic netlist excerpt (pin names and nets, part order shuffled) for the footprints in the layout excerpt that follows; sources: Cadence DE-HDL packaged netlist, KiCad conversion of 04192023_DAF0TMB3IC0_F0TG_MB_C_brd_V02_OCP.brd

R244  Q_RES  0 5% CHIP  pkg 0402LF  page 82 : A = IRQ_BMC_SMI_N ; B = IRQ_BMC_SMI_R_N
R8233  Q_RES  1K 1% CHIP  pkg 0402LF  page 217 : A = P3V3_AUX ; B = PWRGD_PVDDCR_CPU1_P1_R

(kicad_pcb
	(version 20260206)
	(generator "pcbnew")
	(generator_version "10.0")
	(general
		(thickness 1.6)
		(legacy_teardrops no)
	)
	(paper "A4")
	(title_block
		(title "04192023_DAF0TMB3IC0_F0TG_MB_C_brd_V02_OCP.brd")
		(comment 1 "Grand Teton / footprints 6314-6315 of 8354")
	)
	(layers
		(0 "F.Cu" signal "TOP")
		(4 "In1.Cu" signal "GND")
		(6 "In2.Cu" signal "IN1")
		(8 "In3.Cu" signal "GND1")
		(10 "In4.Cu" signal "IN2")
		(12 "In5.Cu" signal "GND2")
		(14 "In6.Cu" signal "IN3")
		(16 "In7.Cu" signal "GND3")
		(18 "In8.Cu" signal "VCC")
		(20 "In9.Cu" signal "VCC1")
		(22 "In10.Cu" signal "GND4")
		(24 "In11.Cu" signal "IN4")
		(26 "In12.Cu" signal "GND5")
		(28 "In13.Cu" signal "IN5")
		(30 "In14.Cu" signal "GND6")
		(32 "In15.Cu" signal "IN6")
		(34 "In16.Cu" signal "GND7")
		(2 "B.Cu" signal "BOTTOM")
		(9 "F.Adhes" user "F.Adhesive")
		(11 "B.Adhes" user "B.Adhesive")
		(13 "F.Paste" user "Package Geometry/Pastemask Top")
		(15 "B.Paste" user "Package Geometry/Pastemask Bottom")
		(5 "F.SilkS" user "Ref Des/Silkscreen Top")
		(7 "B.SilkS" user "Ref Des/Silkscreen Bottom")
		(1 "F.Mask" user "Board Geometry/Soldermask Top")
		(3 "B.Mask" user "Board Geometry/Soldermask Bottom")
		(17 "Dwgs.User" user "User.Drawings")
		(19 "Cmts.User" user "User.Comments")
		(21 "Eco1.User" user "User.Eco1")
		(23 "Eco2.User" user "User.Eco2")
		(25 "Edge.Cuts" user "Board Geometry/Outline")
		(27 "Margin" user)
		(31 "F.CrtYd" user "Package Geometry/Place Bound Top")
		(29 "B.CrtYd" user "Package Geometry/Place Bound Bottom")
		(35 "F.Fab" user "Ref Des/Assembly Top")
		(33 "B.Fab" user "Ref Des/Assembly Bottom")
	)
	(footprint ""
		(layer "B.Cu")
		(at 25.146 -367.157 90)
		(property "Reference" "R8233"
			(at 0 0 90)
			(layer "B.SilkS")
			(hide yes)
			(effects
				(font
					(size 1.27 1.27)
				)
				(justify mirror)
			)
		)
		(property "Value" ""
			(at 0 0 90)
			(layer "B.Fab")
			(effects
				(font
					(size 1.27 1.27)
				)
				(justify mirror)
			)
		)
		(duplicate_pad_numbers_are_jumpers no)
		(fp_line
			(start 0.7874 -0.4064)
			(end -0.7874 -0.4064)
			(stroke
				(width 0.1524)
				(type default)
			)
			(layer "B.SilkS")
		)
		(fp_line
			(start -0.7874 -0.4064)
			(end -0.7874 0.4064)
			(stroke
				(width 0.1524)
				(type default)
			)
			(layer "B.SilkS")
		)
		(fp_line
			(start 0.7874 0.4064)
			(end 0.7874 -0.4064)
			(stroke
				(width 0.1524)
				(type default)
			)
			(layer "B.SilkS")
		)
		(fp_line
			(start -0.7874 0.4064)
			(end 0.7874 0.4064)
			(stroke
				(width 0.1524)
				(type default)
			)
			(layer "B.SilkS")
		)
		(fp_line
			(start 0.67945 -0.305054)
			(end 0.12065 -0.305054)
			(stroke
				(width 0.1)
				(type default)
			)
			(layer "B.Fab")
		)
		(fp_line
			(start 0.12065 -0.305054)
			(end 0.12065 -0.2794)
			(stroke
				(width 0.1)
				(type default)
			)
			(layer "B.Fab")
		)
		(fp_line
			(start -0.12065 -0.3048)
			(end -0.67945 -0.3048)
			(stroke
				(width 0.1)
				(type default)
			)
			(layer "B.Fab")
		)
		(fp_line
			(start -0.67945 -0.3048)
			(end -0.67945 0.3048)
			(stroke
				(width 0.1)
				(type default)
			)
			(layer "B.Fab")
		)
		(fp_line
			(start 0.12065 -0.2794)
			(end -0.12065 -0.2794)
			(stroke
				(width 0.1)
				(type default)
			)
			(layer "B.Fab")
		)
		(fp_line
			(start -0.12065 -0.2794)
			(end -0.12065 -0.3048)
			(stroke
				(width 0.1)
				(type default)
			)
			(layer "B.Fab")
		)
		(fp_line
			(start 0.12065 0.2794)
			(end 0.12065 0.3048)
			(stroke
				(width 0.1)
				(type default)
			)
			(layer "B.Fab")
		)
		(fp_line
			(start -0.120396 0.2794)
			(end 0.12065 0.2794)
			(stroke
				(width 0.1)
				(type default)
			)
			(layer "B.Fab")
		)
		(fp_line
			(start 0.67945 0.3048)
			(end 0.67945 -0.305054)
			(stroke
				(width 0.1)
				(type default)
			)
			(layer "B.Fab")
		)
		(fp_line
			(start 0.12065 0.3048)
			(end 0.67945 0.3048)
			(stroke
				(width 0.1)
				(type default)
			)
			(layer "B.Fab")
		)
		(fp_line
			(start -0.120396 0.3048)
			(end -0.120396 0.2794)
			(stroke
				(width 0.1)
				(type default)
			)
			(layer "B.Fab")
		)
		(fp_line
			(start -0.67945 0.3048)
			(end -0.120396 0.3048)
			(stroke
				(width 0.1)
				(type default)
			)
			(layer "B.Fab")
		)
		(pad "1" smd circle
			(at 0.40005 0 270)
			(size 0 0)
			(layers "B.Cu" "B.Mask" "B.Paste")
			(net "P3V3_AUX")
		)
		(pad "2" smd circle
			(at -0.40005 0 270)
			(size 0 0)
			(layers "B.Cu" "B.Mask" "B.Paste")
			(net "PWRGD_PVDDCR_CPU1_P1_R")
		)
	)
	(footprint ""
		(layer "B.Cu")
		(at 174.64024 -100.294948 -90)
		(property "Reference" "R244"
			(at 0 0 90)
			(layer "B.SilkS")
			(hide yes)
			(effects
				(font
					(size 1.27 1.27)
				)
				(justify mirror)
			)
		)
		(property "Value" ""
			(at 0 0 90)
			(layer "B.Fab")
			(effects
				(font
					(size 1.27 1.27)
				)
				(justify mirror)
			)
		)
		(duplicate_pad_numbers_are_jumpers no)
		(fp_line
			(start -0.7874 0.4064)
			(end 0.7874 0.4064)
			(stroke
				(width 0.1524)
				(type default)
			)
			(layer "B.SilkS")
		)
		(fp_line
			(start 0.7874 0.4064)
			(end 0.7874 -0.4064)
			(stroke
				(width 0.1524)
				(type default)
			)
			(layer "B.SilkS")
		)
		(fp_line
			(start -0.7874 -0.4064)
			(end -0.7874 0.4064)
			(stroke
				(width 0.1524)
				(type default)
			)
			(layer "B.SilkS")
		)
		(fp_line
			(start 0.7874 -0.4064)
			(end -0.7874 -0.4064)
			(stroke
				(width 0.1524)
				(type default)
			)
			(layer "B.SilkS")
		)
		(fp_line
			(start -0.67945 0.3048)
			(end -0.120396 0.3048)
			(stroke
				(width 0.1)
				(type default)
			)
			(layer "B.Fab")
		)
		(fp_line
			(start -0.120396 0.3048)
			(end -0.120396 0.2794)
			(stroke
				(width 0.1)
				(type default)
			)
			(layer "B.Fab")
		)
		(fp_line
			(start 0.12065 0.3048)
			(end 0.67945 0.3048)
			(stroke
				(width 0.1)
				(type default)
			)
			(layer "B.Fab")
		)
		(fp_line
			(start 0.67945 0.3048)
			(end 0.67945 -0.305054)
			(stroke
				(width 0.1)
				(type default)
			)
			(layer "B.Fab")
		)
		(fp_line
			(start -0.120396 0.2794)
			(end 0.12065 0.2794)
			(stroke
				(width 0.1)
				(type default)
			)
			(layer "B.Fab")
		)
		(fp_line
			(start 0.12065 0.2794)
			(end 0.12065 0.3048)
			(stroke
				(width 0.1)
				(type default)
			)
			(layer "B.Fab")
		)
		(fp_line
			(start -0.12065 -0.2794)
			(end -0.12065 -0.3048)
			(stroke
				(width 0.1)
				(type default)
			)
			(layer "B.Fab")
		)
		(fp_line
			(start 0.12065 -0.2794)
			(end -0.12065 -0.2794)
			(stroke
				(width 0.1)
				(type default)
			)
			(layer "B.Fab")
		)
		(fp_line
			(start -0.67945 -0.3048)
			(end -0.67945 0.3048)
			(stroke
				(width 0.1)
				(type default)
			)
			(layer "B.Fab")
		)
		(fp_line
			(start -0.12065 -0.3048)
			(end -0.67945 -0.3048)
			(stroke
				(width 0.1)
				(type default)
			)
			(layer "B.Fab")
		)
		(fp_line
			(start 0.12065 -0.305054)
			(end 0.12065 -0.2794)
			(stroke
				(width 0.1)
				(type default)
			)
			(layer "B.Fab")
		)
		(fp_line
			(start 0.67945 -0.305054)
			(end 0.12065 -0.305054)
			(stroke
				(width 0.1)
				(type default)
			)
			(layer "B.Fab")
		)
		(pad "1" smd circle
			(at 0.40005 0 90)
			(size 0 0)
			(layers "B.Cu" "B.Mask" "B.Paste")
			(net "IRQ_BMC_SMI_N")
		)
		(pad "2" smd circle
			(at -0.40005 0 90)
			(size 0 0)
			(layers "B.Cu" "B.Mask" "B.Paste")
			(net "IRQ_BMC_SMI_R_N")
		)
	)
)
